# BASEBOARD_FAB2 (Tioga Pass) — schematic netlist excerpt (pin names and nets, part order shuffled) for the footprints in the layout excerpt that follows; sources: Cadence DE-HDL packaged netlist, KiCad conversion of Wiwynn_Tioga_Pass_MB.brd

R3N3  RES  2.0K 1% CHIP  pkg 0402  page 133 : A = GND ; B = PWRGD_PCH_PWROK
C5P36  CAP  47UF 4V 20% X6S  pkg 0805  page 42 : A = PVCCIN_CPU0 ; B = GND
R3P38  RES  64.9 1.0% CHIP  pkg 0402  page 96 : A = PVDDQ_ABC ; B = PWRGD_CPU0_DRAMPWROK_ABC_G

(kicad_pcb
	(version 20260206)
	(generator "pcbnew")
	(generator_version "10.0")
	(general
		(thickness 1.6)
		(legacy_teardrops no)
	)
	(paper "A4")
	(title_block
		(title "Wiwynn_Tioga_Pass_MB.brd")
		(comment 1 "Tioga Pass / footprints 2887-2889 of 4770")
	)
	(layers
		(0 "F.Cu" signal "TOP")
		(4 "In1.Cu" signal "L2GND")
		(6 "In2.Cu" signal "L3")
		(8 "In3.Cu" signal "L4GND")
		(10 "In4.Cu" signal "L5")
		(12 "In5.Cu" signal "L6GND")
		(14 "In6.Cu" signal "L7VCC")
		(16 "In7.Cu" signal "L8VCC")
		(18 "In8.Cu" signal "L9GND")
		(20 "In9.Cu" signal "L10")
		(22 "In10.Cu" signal "L11GND")
		(24 "In11.Cu" signal "L12")
		(26 "In12.Cu" signal "L13GND")
		(2 "B.Cu" signal "BOTTOM")
		(9 "F.Adhes" user "F.Adhesive")
		(11 "B.Adhes" user "B.Adhesive")
		(13 "F.Paste" user "Package Geometry/Pastemask Top")
		(15 "B.Paste" user "Package Geometry/Pastemask Bottom")
		(5 "F.SilkS" user "Ref Des/Silkscreen Top")
		(7 "B.SilkS" user "Ref Des/Silkscreen Bottom")
		(1 "F.Mask" user "Board Geometry/Soldermask Top")
		(3 "B.Mask" user "Board Geometry/Soldermask Bottom")
		(17 "Dwgs.User" user "User.Drawings")
		(19 "Cmts.User" user "User.Comments")
		(21 "Eco1.User" user "User.Eco1")
		(23 "Eco2.User" user "User.Eco2")
		(25 "Edge.Cuts" user "Board Geometry/Outline")
		(27 "Margin" user)
		(31 "F.CrtYd" user "Package Geometry/Place Bound Top")
		(29 "B.CrtYd" user "Package Geometry/Place Bound Bottom")
		(35 "F.Fab" user "Ref Des/Assembly Top")
		(33 "B.Fab" user "Ref Des/Assembly Bottom")
	)
	(footprint ""
		(layer "B.Cu")
		(at 372.869968 -51.34229 180)
		(property "Reference" "R3P38"
			(at 0 0 0)
			(layer "B.SilkS")
			(hide yes)
			(effects
				(font
					(size 1.27 1.27)
				)
				(justify mirror)
			)
		)
		(property "Value" ""
			(at 0 0 0)
			(layer "B.Fab")
			(effects
				(font
					(size 1.27 1.27)
				)
				(justify mirror)
			)
		)
		(duplicate_pad_numbers_are_jumpers no)
		(fp_poly
			(pts
				(xy 0.2794 -0.1016) (xy -0.2794 -0.1016) (xy -0.2794 0.9906) (xy 0.2794 0.9906)
			)
			(stroke
				(width 0)
				(type default)
			)
			(fill no)
			(layer "B.CrtYd")
		)
		(fp_line
			(start 0.2794 0.9906)
			(end -0.2794 0.9906)
			(stroke
				(width 0.1)
				(type default)
			)
			(layer "B.Fab")
		)
		(fp_line
			(start 0.2794 -0.1016)
			(end 0.2794 0.9906)
			(stroke
				(width 0.1)
				(type default)
			)
			(layer "B.Fab")
		)
		(fp_line
			(start -0.2794 0.9906)
			(end -0.2794 -0.1016)
			(stroke
				(width 0.1)
				(type default)
			)
			(layer "B.Fab")
		)
		(fp_line
			(start -0.2794 -0.1016)
			(end 0.2794 -0.1016)
			(stroke
				(width 0.1)
				(type default)
			)
			(layer "B.Fab")
		)
		(pad "1" smd rect
			(at 0 0)
			(size 0.508 0.508)
			(layers "B.Cu" "B.Mask" "B.Paste")
			(net "PVDDQ_ABC")
		)
		(pad "2" smd rect
			(at 0 0.889)
			(size 0.508 0.508)
			(layers "B.Cu" "B.Mask" "B.Paste")
			(net "PWRGD_CPU0_DRAMPWROK_ABC_G")
		)
		(zone
			(layer "B.Cu")
			(hatch none 0.5)
			(connect_pads
				(clearance 0)
			)
			(min_thickness 0.25)
			(keepout
				(tracks not_allowed)
				(vias allowed)
				(pads allowed)
				(copperpour not_allowed)
				(footprints allowed)
			)
			(placement
				(enabled no)
				(sheetname "")
			)
			(fill
				(thermal_gap 0.5)
				(thermal_bridge_width 0.5)
				(island_removal_mode 0)
			)
			(polygon
				(pts
					(xy 372.615968 -51.97729) (xy 373.123968 -51.97729) (xy 373.123968 -51.59629) (xy 372.615968 -51.59629)
				)
			)
		)
		(zone
			(layer "B.Cu")
			(hatch none 0.5)
			(connect_pads
				(clearance 0)
			)
			(min_thickness 0.25)
			(keepout
				(tracks allowed)
				(vias not_allowed)
				(pads allowed)
				(copperpour not_allowed)
				(footprints allowed)
			)
			(placement
				(enabled no)
				(sheetname "")
			)
			(fill
				(thermal_gap 0.5)
				(thermal_bridge_width 0.5)
				(island_removal_mode 0)
			)
			(polygon
				(pts
					(xy 372.615968 -51.59629) (xy 373.123968 -51.59629) (xy 373.123968 -51.97729) (xy 372.615968 -51.97729)
				)
			)
		)
	)
	(footprint ""
		(layer "B.Cu")
		(at 260.377686 -73.51014)
		(property "Reference" "C5P36"
			(at 0 0 0)
			(layer "B.SilkS")
			(hide yes)
			(effects
				(font
					(size 1.27 1.27)
				)
				(justify mirror)
			)
		)
		(property "Value" ""
			(at 0 0 0)
			(layer "B.Fab")
			(effects
				(font
					(size 1.27 1.27)
				)
				(justify mirror)
			)
		)
		(duplicate_pad_numbers_are_jumpers no)
		(fp_poly
			(pts
				(xy 0.7239 -0.2159) (xy -0.7239 -0.2159) (xy -0.7239 1.9939) (xy 0.7239 1.9939)
			)
			(stroke
				(width 0)
				(type default)
			)
			(fill no)
			(layer "B.CrtYd")
		)
		(fp_line
			(start -0.7239 -0.2159)
			(end 0.7239 -0.2159)
			(stroke
				(width 0.1)
				(type default)
			)
			(layer "B.Fab")
		)
		(fp_line
			(start -0.7239 1.9939)
			(end -0.7239 -0.2159)
			(stroke
				(width 0.1)
				(type default)
			)
			(layer "B.Fab")
		)
		(fp_line
			(start 0.7239 -0.2159)
			(end 0.7239 1.9939)
			(stroke
				(width 0.1)
				(type default)
			)
			(layer "B.Fab")
		)
		(fp_line
			(start 0.7239 1.9939)
			(end -0.7239 1.9939)
			(stroke
				(width 0.1)
				(type default)
			)
			(layer "B.Fab")
		)
		(pad "1" smd rect
			(at 0 0 180)
			(size 1.27 1.016)
			(layers "B.Cu" "B.Mask" "B.Paste")
			(net "PVCCIN_CPU0")
		)
		(pad "2" smd rect
			(at 0 1.778 180)
			(size 1.27 1.016)
			(layers "B.Cu" "B.Mask" "B.Paste")
			(net "GND")
		)
		(zone
			(layer "B.Cu")
			(hatch none 0.5)
			(connect_pads
				(clearance 0)
			)
			(min_thickness 0.25)
			(keepout
				(tracks not_allowed)
				(vias allowed)
				(pads allowed)
				(copperpour not_allowed)
				(footprints allowed)
			)
			(placement
				(enabled no)
				(sheetname "")
			)
			(fill
				(thermal_gap 0.5)
				(thermal_bridge_width 0.5)
				(island_removal_mode 0)
			)
			(polygon
				(pts
					(xy 261.012686 -73.00214) (xy 259.742686 -73.00214) (xy 259.742686 -72.24014) (xy 261.012686 -72.24014)
				)
			)
		)
	)
	(footprint ""
		(layer "B.Cu")
		(at 374.8278 -102.0826 90)
		(property "Reference" "R3N3"
			(at 0 0 90)
			(layer "B.SilkS")
			(hide yes)
			(effects
				(font
					(size 1.27 1.27)
				)
				(justify mirror)
			)
		)
		(property "Value" ""
			(at 0 0 90)
			(layer "B.Fab")
			(effects
				(font
					(size 1.27 1.27)
				)
				(justify mirror)
			)
		)
		(duplicate_pad_numbers_are_jumpers no)
		(fp_poly
			(pts
				(xy 0.2794 -0.1016) (xy -0.2794 -0.1016) (xy -0.2794 0.9906) (xy 0.2794 0.9906)
			)
			(stroke
				(width 0)
				(type default)
			)
			(fill no)
			(layer "B.CrtYd")
		)
		(fp_line
			(start 0.2794 -0.1016)
			(end 0.2794 0.9906)
			(stroke
				(width 0.1)
				(type default)
			)
			(layer "B.Fab")
		)
		(fp_line
			(start -0.2794 -0.1016)
			(end 0.2794 -0.1016)
			(stroke
				(width 0.1)
				(type default)
			)
			(layer "B.Fab")
		)
		(fp_line
			(start 0.2794 0.9906)
			(end -0.2794 0.9906)
			(stroke
				(width 0.1)
				(type default)
			)
			(layer "B.Fab")
		)
		(fp_line
			(start -0.2794 0.9906)
			(end -0.2794 -0.1016)
			(stroke
				(width 0.1)
				(type default)
			)
			(layer "B.Fab")
		)
		(pad "1" smd rect
			(at 0 0 270)
			(size 0.508 0.508)
			(layers "B.Cu" "B.Mask" "B.Paste")
			(net "GND")
		)
		(pad "2" smd rect
			(at 0 0.889 270)
			(size 0.508 0.508)
			(layers "B.Cu" "B.Mask" "B.Paste")
			(net "PWRGD_PCH_PWROK")
		)
		(zone
			(layer "B.Cu")
			(hatch none 0.5)
			(connect_pads
				(clearance 0)
			)
			(min_thickness 0.25)
			(keepout
				(tracks allowed)
				(vias not_allowed)
				(pads allowed)
				(copperpour not_allowed)
				(footprints allowed)
			)
			(placement
				(enabled no)
				(sheetname "")
			)
			(fill
				(thermal_gap 0.5)
				(thermal_bridge_width 0.5)
				(island_removal_mode 0)
			)
			(polygon
				(pts
					(xy 375.0818 -102.3366) (xy 375.0818 -101.8286) (xy 375.4628 -101.8286) (xy 375.4628 -102.3366)
				)
			)
		)
		(zone
			(layer "B.Cu")
			(hatch none 0.5)
			(connect_pads
				(clearance 0)
			)
			(min_thickness 0.25)
			(keepout
				(tracks not_allowed)
				(vias allowed)
				(pads allowed)
				(copperpour not_allowed)
				(footprints allowed)
			)
			(placement
				(enabled no)
				(sheetname "")
			)
			(fill
				(thermal_gap 0.5)
				(thermal_bridge_width 0.5)
				(island_removal_mode 0)
			)
			(polygon
				(pts
					(xy 375.4628 -102.3366) (xy 375.4628 -101.8286) (xy 375.0818 -101.8286) (xy 375.0818 -102.3366)
				)
			)
		)
	)
)
